(kicad_pcb
	(version 20260206)
	(generator "pcbnew")
	(generator_version "10.0")
	(general
		(thickness 1.6)
		(legacy_teardrops no)
	)
	(paper "A4")
	(title_block
		(title "panther-plus-userver — 13130-1b_20150205.brd")
		(comment 1 "Honey Badger (Wiwynn) / footprints 557-564 of 1509")
	)
	(layers
		(0 "F.Cu" signal "TOP")
		(4 "In1.Cu" signal "L2")
		(6 "In2.Cu" signal "L3")
		(8 "In3.Cu" signal "L4")
		(10 "In4.Cu" signal "L5")
		(12 "In5.Cu" signal "L6")
		(14 "In6.Cu" signal "L7")
		(16 "In7.Cu" signal "L8")
		(18 "In8.Cu" signal "L9")
		(20 "In9.Cu" signal "L10")
		(22 "In10.Cu" signal "L11")
		(2 "B.Cu" signal "BOTTOM")
		(9 "F.Adhes" user "F.Adhesive")
		(11 "B.Adhes" user "B.Adhesive")
		(13 "F.Paste" user "Package Geometry/Pastemask Top")
		(15 "B.Paste" user "Package Geometry/Pastemask Bottom")
		(5 "F.SilkS" user "Ref Des/Silkscreen Top")
		(7 "B.SilkS" user "Ref Des/Silkscreen Bottom")
		(1 "F.Mask" user "Board Geometry/Soldermask Top")
		(3 "B.Mask" user "Board Geometry/Soldermask Bottom")
		(17 "Dwgs.User" user "User.Drawings")
		(19 "Cmts.User" user "User.Comments")
		(21 "Eco1.User" user "User.Eco1")
		(23 "Eco2.User" user "User.Eco2")
		(25 "Edge.Cuts" user "Board Geometry/Outline")
		(27 "Margin" user)
		(31 "F.CrtYd" user "Package Geometry/Place Bound Top")
		(29 "B.CrtYd" user "Package Geometry/Place Bound Bottom")
		(35 "F.Fab" user "Ref Des/Assembly Top")
		(33 "B.Fab" user "Ref Des/Assembly Bottom")
	)
	(footprint ""
		(layer "F.Cu")
		(at 197.4596 -65.0748 -90)
		(property "Reference" "PC171"
			(at 0 0 270)
			(layer "F.SilkS")
			(hide yes)
			(effects
				(font
					(size 1.27 1.27)
				)
			)
		)
		(property "Value" "SC22U6D3V5MX-2GP"
			(at 0 -4.9022 270)
			(unlocked yes)
			(layer "F.Fab")
			(hide yes)
			(effects
				(font
					(size 1.016 1.016)
					(thickness 0.1524)
				)
			)
		)
		(property "Device Type" "C805H58"
			(at 0 -6.8072 270)
			(unlocked yes)
			(layer "F.Fab")
			(hide yes)
			(effects
				(font
					(size 1.016 1.016)
					(thickness 0.1524)
				)
			)
		)
		(duplicate_pad_numbers_are_jumpers no)
		(fp_line
			(start 0.6096 0)
			(end -0.6096 0)
			(stroke
				(width 0.3048)
				(type default)
			)
			(layer "F.SilkS")
		)
		(fp_poly
			(pts
				(xy -0.9017 1.4351) (xy 0.9017 1.4351) (xy 0.9017 -1.4351) (xy -0.9017 -1.4351)
			)
			(stroke
				(width 0)
				(type default)
			)
			(fill no)
			(layer "F.CrtYd")
		)
		(fp_poly
			(pts
				(xy 0.9017 1.4351) (xy 0.9017 -1.4351) (xy -0.9017 -1.4351) (xy -0.9017 1.4351)
			)
			(stroke
				(width 0)
				(type default)
			)
			(fill no)
			(layer "F.Fab")
		)
		(pad "1" smd rect
			(at 0 -0.8382 270)
			(size 1.5494 0.9398)
			(layers "F.Cu" "F.Mask" "F.Paste")
			(net "PV_VDDR")
		)
		(pad "2" smd rect
			(at 0 0.8382 270)
			(size 1.5494 0.9398)
			(layers "F.Cu" "F.Mask" "F.Paste")
			(net "GND")
		)
	)
	(footprint ""
		(layer "F.Cu")
		(at 25.25268 -64.8716 180)
		(property "Reference" "PR13"
			(at 0 0 180)
			(layer "F.SilkS")
			(hide yes)
			(effects
				(font
					(size 1.27 1.27)
				)
			)
		)
		(property "Value" "0R3J-0-U-GP"
			(at -0.0254 -2.0193 180)
			(unlocked yes)
			(layer "F.Fab")
			(hide yes)
			(effects
				(font
					(size 1.016 1.016)
					(thickness 0.1524)
				)
			)
		)
		(property "Device Type" "R603H22"
			(at -0.0254 -3.5433 180)
			(unlocked yes)
			(layer "F.Fab")
			(hide yes)
			(effects
				(font
					(size 1.016 1.016)
					(thickness 0.1524)
				)
			)
		)
		(duplicate_pad_numbers_are_jumpers no)
		(fp_line
			(start 0.4318 0)
			(end 0.2032 0)
			(stroke
				(width 0.2032)
				(type default)
			)
			(layer "F.SilkS")
		)
		(fp_line
			(start -0.2032 0)
			(end -0.4191 0)
			(stroke
				(width 0.2032)
				(type default)
			)
			(layer "F.SilkS")
		)
		(fp_rect
			(start -0.635 1.1811)
			(end 0.635 -1.1811)
			(stroke
				(width 0)
				(type default)
			)
			(fill no)
			(layer "F.CrtYd")
		)
		(fp_rect
			(start -0.635 1.1811)
			(end 0.635 -1.1811)
			(stroke
				(width 0)
				(type default)
			)
			(fill no)
			(layer "F.Fab")
		)
		(pad "1" smd custom
			(at 0 -0.6604 180)
			(size 0.19685 0.19685)
			(layers "F.Cu" "F.Mask" "F.Paste")
			(net "VR_PVNN_GH")
			(options
				(clearance outline)
				(anchor circle)
			)
			(primitives
				(gr_poly
					(pts
						(arc
							(start 0.508 -0.2921)
							(mid 0.478242 -0.363942)
							(end 0.4064 -0.3937)
						)
						(arc
							(start -0.4064 -0.3937)
							(mid -0.478242 -0.363942)
							(end -0.508 -0.2921)
						)
						(arc
							(start -0.508 0.2921)
							(mid -0.478242 0.363942)
							(end -0.4064 0.3937)
						)
						(arc
							(start 0.4064 0.3937)
							(mid 0.478242 0.363942)
							(end 0.508 0.2921)
						)
					)
					(width 0)
					(fill yes)
				)
			)
		)
		(pad "2" smd custom
			(at 0 0.6604 180)
			(size 0.19685 0.19685)
			(layers "F.Cu" "F.Mask" "F.Paste")
			(net "VR_PVNN_GH_R")
			(options
				(clearance outline)
				(anchor circle)
			)
			(primitives
				(gr_poly
					(pts
						(arc
							(start 0.508 -0.2921)
							(mid 0.478242 -0.363942)
							(end 0.4064 -0.3937)
						)
						(arc
							(start -0.4064 -0.3937)
							(mid -0.478242 -0.363942)
							(end -0.508 -0.2921)
						)
						(arc
							(start -0.508 0.2921)
							(mid -0.478242 0.363942)
							(end -0.4064 0.3937)
						)
						(arc
							(start 0.4064 0.3937)
							(mid 0.478242 0.363942)
							(end 0.508 0.2921)
						)
					)
					(width 0)
					(fill yes)
				)
			)
		)
	)
	(footprint ""
		(layer "F.Cu")
		(at 73.66 -26.416 -90)
		(property "Reference" "R358"
			(at 0 0 270)
			(layer "F.SilkS")
			(hide yes)
			(effects
				(font
					(size 1.27 1.27)
				)
			)
		)
		(property "Value" "10KR2F-2-GP"
			(at 0.064008 -3.993896 270)
			(unlocked yes)
			(layer "F.Fab")
			(hide yes)
			(effects
				(font
					(size 1.016 1.016)
					(thickness 0.1524)
				)
			)
		)
		(property "Device Type" "R402H16"
			(at 0.064008 -5.517896 270)
			(unlocked yes)
			(layer "F.Fab")
			(hide yes)
			(effects
				(font
					(size 1.016 1.016)
					(thickness 0.1524)
				)
			)
		)
		(duplicate_pad_numbers_are_jumpers no)
		(fp_rect
			(start -0.381 0.8382)
			(end 0.381 -0.8382)
			(stroke
				(width 0)
				(type default)
			)
			(fill no)
			(layer "F.CrtYd")
		)
		(fp_rect
			(start -0.381 0.8382)
			(end 0.381 -0.8382)
			(stroke
				(width 0)
				(type default)
			)
			(fill no)
			(layer "F.Fab")
		)
		(pad "1" smd custom
			(at 0 -0.4318 270)
			(size 0.127 0.127)
			(layers "F.Cu" "F.Mask" "F.Paste")
			(net "P3V3_CPU")
			(options
				(clearance outline)
				(anchor circle)
			)
			(primitives
				(gr_poly
					(pts
						(arc
							(start -0.2032 -0.2794)
							(mid -0.239121 -0.264521)
							(end -0.254 -0.2286)
						)
						(arc
							(start -0.254 0.2286)
							(mid -0.239121 0.264521)
							(end -0.2032 0.2794)
						)
						(arc
							(start 0.2032 0.2794)
							(mid 0.239121 0.264521)
							(end 0.254 0.2286)
						)
						(arc
							(start 0.254 -0.2286)
							(mid 0.239121 -0.264521)
							(end 0.2032 -0.2794)
						)
					)
					(width 0)
					(fill yes)
				)
			)
		)
		(pad "2" smd custom
			(at 0 0.4318 270)
			(size 0.127 0.127)
			(layers "F.Cu" "F.Mask" "F.Paste")
			(net "CPU_RSMRST#")
			(options
				(clearance outline)
				(anchor circle)
			)
			(primitives
				(gr_poly
					(pts
						(arc
							(start -0.2032 -0.2794)
							(mid -0.239121 -0.264521)
							(end -0.254 -0.2286)
						)
						(arc
							(start -0.254 0.2286)
							(mid -0.239121 0.264521)
							(end -0.2032 0.2794)
						)
						(arc
							(start 0.2032 0.2794)
							(mid 0.239121 0.264521)
							(end 0.254 0.2286)
						)
						(arc
							(start 0.254 -0.2286)
							(mid 0.239121 -0.264521)
							(end 0.2032 -0.2794)
						)
					)
					(width 0)
					(fill yes)
				)
			)
		)
	)
	(footprint ""
		(layer "F.Cu")
		(at 176.403 -57.15 180)
		(property "Reference" "R171"
			(at 0 0 180)
			(layer "F.SilkS")
			(hide yes)
			(effects
				(font
					(size 1.27 1.27)
				)
			)
		)
		(property "Value" "4K7R2F-GP"
			(at 0.064008 -3.993896 180)
			(unlocked yes)
			(layer "F.Fab")
			(hide yes)
			(effects
				(font
					(size 1.016 1.016)
					(thickness 0.1524)
				)
			)
		)
		(property "Device Type" "R402H16"
			(at 0.064008 -5.517896 180)
			(unlocked yes)
			(layer "F.Fab")
			(hide yes)
			(effects
				(font
					(size 1.016 1.016)
					(thickness 0.1524)
				)
			)
		)
		(duplicate_pad_numbers_are_jumpers no)
		(fp_rect
			(start -0.381 0.8382)
			(end 0.381 -0.8382)
			(stroke
				(width 0)
				(type default)
			)
			(fill no)
			(layer "F.CrtYd")
		)
		(fp_rect
			(start -0.381 0.8382)
			(end 0.381 -0.8382)
			(stroke
				(width 0)
				(type default)
			)
			(fill no)
			(layer "F.Fab")
		)
		(pad "1" smd custom
			(at 0 -0.4318 180)
			(size 0.127 0.127)
			(layers "F.Cu" "F.Mask" "F.Paste")
			(net "EEPROM_A0")
			(options
				(clearance outline)
				(anchor circle)
			)
			(primitives
				(gr_poly
					(pts
						(arc
							(start -0.2032 -0.2794)
							(mid -0.239121 -0.264521)
							(end -0.254 -0.2286)
						)
						(arc
							(start -0.254 0.2286)
							(mid -0.239121 0.264521)
							(end -0.2032 0.2794)
						)
						(arc
							(start 0.2032 0.2794)
							(mid 0.239121 0.264521)
							(end 0.254 0.2286)
						)
						(arc
							(start 0.254 -0.2286)
							(mid 0.239121 -0.264521)
							(end 0.2032 -0.2794)
						)
					)
					(width 0)
					(fill yes)
				)
			)
		)
		(pad "2" smd custom
			(at 0 0.4318 180)
			(size 0.127 0.127)
			(layers "F.Cu" "F.Mask" "F.Paste")
			(net "GND")
			(options
				(clearance outline)
				(anchor circle)
			)
			(primitives
				(gr_poly
					(pts
						(arc
							(start -0.2032 -0.2794)
							(mid -0.239121 -0.264521)
							(end -0.254 -0.2286)
						)
						(arc
							(start -0.254 0.2286)
							(mid -0.239121 0.264521)
							(end -0.2032 0.2794)
						)
						(arc
							(start 0.2032 0.2794)
							(mid 0.239121 0.264521)
							(end 0.254 0.2286)
						)
						(arc
							(start 0.254 -0.2286)
							(mid 0.239121 -0.264521)
							(end 0.2032 -0.2794)
						)
					)
					(width 0)
					(fill yes)
				)
			)
		)
	)
	(footprint ""
		(layer "F.Cu")
		(at 15.8496 -59.8932 -90)
		(property "Reference" "PR42"
			(at 0 0 270)
			(layer "F.SilkS")
			(hide yes)
			(effects
				(font
					(size 1.27 1.27)
				)
			)
		)
		(property "Value" "0R2J-2-GP"
			(at 1.7907 -1.1176 270)
			(unlocked yes)
			(layer "F.Fab")
			(hide yes)
			(effects
				(font
					(size 1.016 1.016)
					(thickness 0.1524)
				)
			)
		)
		(property "Device Type" "R402H16"
			(at 1.7907 -2.6416 270)
			(unlocked yes)
			(layer "F.Fab")
			(hide yes)
			(effects
				(font
					(size 1.016 1.016)
					(thickness 0.1524)
				)
			)
		)
		(duplicate_pad_numbers_are_jumpers no)
		(fp_rect
			(start -0.381 0.8382)
			(end 0.381 -0.8382)
			(stroke
				(width 0)
				(type default)
			)
			(fill no)
			(layer "F.CrtYd")
		)
		(fp_rect
			(start -0.381 0.8382)
			(end 0.381 -0.8382)
			(stroke
				(width 0)
				(type default)
			)
			(fill no)
			(layer "F.Fab")
		)
		(pad "1" smd custom
			(at 0 -0.4318 270)
			(size 0.127 0.127)
			(layers "F.Cu" "F.Mask" "F.Paste")
			(net "VR_95831_ALERT_N")
			(options
				(clearance outline)
				(anchor circle)
			)
			(primitives
				(gr_poly
					(pts
						(arc
							(start -0.2032 -0.2794)
							(mid -0.239121 -0.264521)
							(end -0.254 -0.2286)
						)
						(arc
							(start -0.254 0.2286)
							(mid -0.239121 0.264521)
							(end -0.2032 0.2794)
						)
						(arc
							(start 0.2032 0.2794)
							(mid 0.239121 0.264521)
							(end 0.254 0.2286)
						)
						(arc
							(start 0.254 -0.2286)
							(mid 0.239121 -0.264521)
							(end 0.2032 -0.2794)
						)
					)
					(width 0)
					(fill yes)
				)
			)
		)
		(pad "2" smd custom
			(at 0 0.4318 270)
			(size 0.127 0.127)
			(layers "F.Cu" "F.Mask" "F.Paste")
			(net "SVID_CPU_ALERT#")
			(options
				(clearance outline)
				(anchor circle)
			)
			(primitives
				(gr_poly
					(pts
						(arc
							(start -0.2032 -0.2794)
							(mid -0.239121 -0.264521)
							(end -0.254 -0.2286)
						)
						(arc
							(start -0.254 0.2286)
							(mid -0.239121 0.264521)
							(end -0.2032 0.2794)
						)
						(arc
							(start 0.2032 0.2794)
							(mid 0.239121 0.264521)
							(end 0.254 0.2286)
						)
						(arc
							(start 0.254 -0.2286)
							(mid 0.239121 -0.264521)
							(end 0.2032 -0.2794)
						)
					)
					(width 0)
					(fill yes)
				)
			)
		)
	)
	(footprint ""
		(layer "F.Cu")
		(at 163.7792 -48.895 -90)
		(property "Reference" "R494"
			(at 0 0 270)
			(layer "F.SilkS")
			(hide yes)
			(effects
				(font
					(size 1.27 1.27)
				)
			)
		)
		(property "Value" "0R2J-2-GP"
			(at 1.7907 -1.1176 270)
			(unlocked yes)
			(layer "F.Fab")
			(hide yes)
			(effects
				(font
					(size 1.016 1.016)
					(thickness 0.1524)
				)
			)
		)
		(property "Device Type" "R402H16"
			(at 1.7907 -2.6416 270)
			(unlocked yes)
			(layer "F.Fab")
			(hide yes)
			(effects
				(font
					(size 1.016 1.016)
					(thickness 0.1524)
				)
			)
		)
		(duplicate_pad_numbers_are_jumpers no)
		(fp_rect
			(start -0.381 0.8382)
			(end 0.381 -0.8382)
			(stroke
				(width 0)
				(type default)
			)
			(fill no)
			(layer "F.CrtYd")
		)
		(fp_rect
			(start -0.381 0.8382)
			(end 0.381 -0.8382)
			(stroke
				(width 0)
				(type default)
			)
			(fill no)
			(layer "F.Fab")
		)
		(pad "1" smd custom
			(at 0 -0.4318 270)
			(size 0.127 0.127)
			(layers "F.Cu" "F.Mask" "F.Paste")
			(net "JTAG_CPU_PLD_TDO")
			(options
				(clearance outline)
				(anchor circle)
			)
			(primitives
				(gr_poly
					(pts
						(arc
							(start -0.2032 -0.2794)
							(mid -0.239121 -0.264521)
							(end -0.254 -0.2286)
						)
						(arc
							(start -0.254 0.2286)
							(mid -0.239121 0.264521)
							(end -0.2032 0.2794)
						)
						(arc
							(start 0.2032 0.2794)
							(mid 0.239121 0.264521)
							(end 0.254 0.2286)
						)
						(arc
							(start 0.254 -0.2286)
							(mid 0.239121 -0.264521)
							(end 0.2032 -0.2794)
						)
					)
					(width 0)
					(fill yes)
				)
			)
		)
		(pad "2" smd custom
			(at 0 0.4318 270)
			(size 0.127 0.127)
			(layers "F.Cu" "F.Mask" "F.Paste")
			(net "JTAG_PLD_TDO")
			(options
				(clearance outline)
				(anchor circle)
			)
			(primitives
				(gr_poly
					(pts
						(arc
							(start -0.2032 -0.2794)
							(mid -0.239121 -0.264521)
							(end -0.254 -0.2286)
						)
						(arc
							(start -0.254 0.2286)
							(mid -0.239121 0.264521)
							(end -0.2032 0.2794)
						)
						(arc
							(start 0.2032 0.2794)
							(mid 0.239121 0.264521)
							(end 0.254 0.2286)
						)
						(arc
							(start 0.254 -0.2286)
							(mid 0.239121 -0.264521)
							(end 0.2032 -0.2794)
						)
					)
					(width 0)
					(fill yes)
				)
			)
		)
	)
	(footprint ""
		(layer "F.Cu")
		(at 168.275 -48.133 90)
		(property "Reference" "R211"
			(at 0 0 90)
			(layer "F.SilkS")
			(hide yes)
			(effects
				(font
					(size 1.27 1.27)
				)
			)
		)
		(property "Value" "0R2J-2-GP"
			(at 1.7907 -1.1176 90)
			(unlocked yes)
			(layer "F.Fab")
			(hide yes)
			(effects
				(font
					(size 1.016 1.016)
					(thickness 0.1524)
				)
			)
		)
		(property "Device Type" "R402H16"
			(at 1.7907 -2.6416 90)
			(unlocked yes)
			(layer "F.Fab")
			(hide yes)
			(effects
				(font
					(size 1.016 1.016)
					(thickness 0.1524)
				)
			)
		)
		(duplicate_pad_numbers_are_jumpers no)
		(fp_rect
			(start -0.381 0.8382)
			(end 0.381 -0.8382)
			(stroke
				(width 0)
				(type default)
			)
			(fill no)
			(layer "F.CrtYd")
		)
		(fp_rect
			(start -0.381 0.8382)
			(end 0.381 -0.8382)
			(stroke
				(width 0)
				(type default)
			)
			(fill no)
			(layer "F.Fab")
		)
		(pad "1" smd custom
			(at 0 -0.4318 90)
			(size 0.127 0.127)
			(layers "F.Cu" "F.Mask" "F.Paste")
			(net "JTAG_RST#")
			(options
				(clearance outline)
				(anchor circle)
			)
			(primitives
				(gr_poly
					(pts
						(arc
							(start -0.2032 -0.2794)
							(mid -0.239121 -0.264521)
							(end -0.254 -0.2286)
						)
						(arc
							(start -0.254 0.2286)
							(mid -0.239121 0.264521)
							(end -0.2032 0.2794)
						)
						(arc
							(start 0.2032 0.2794)
							(mid 0.239121 0.264521)
							(end 0.254 0.2286)
						)
						(arc
							(start 0.254 -0.2286)
							(mid 0.239121 -0.264521)
							(end 0.2032 -0.2794)
						)
					)
					(width 0)
					(fill yes)
				)
			)
		)
		(pad "2" smd custom
			(at 0 0.4318 90)
			(size 0.127 0.127)
			(layers "F.Cu" "F.Mask" "F.Paste")
			(net "JTAG_RST_D#")
			(options
				(clearance outline)
				(anchor circle)
			)
			(primitives
				(gr_poly
					(pts
						(arc
							(start -0.2032 -0.2794)
							(mid -0.239121 -0.264521)
							(end -0.254 -0.2286)
						)
						(arc
							(start -0.254 0.2286)
							(mid -0.239121 0.264521)
							(end -0.2032 0.2794)
						)
						(arc
							(start 0.2032 0.2794)
							(mid 0.239121 0.264521)
							(end 0.254 0.2286)
						)
						(arc
							(start 0.254 -0.2286)
							(mid 0.239121 -0.264521)
							(end 0.2032 -0.2794)
						)
					)
					(width 0)
					(fill yes)
				)
			)
		)
	)
	(footprint ""
		(layer "F.Cu")
		(at 18.415 -23.749)
		(property "Reference" "PC50"
			(at 0 0 0)
			(layer "F.SilkS")
			(hide yes)
			(effects
				(font
					(size 1.27 1.27)
				)
			)
		)
		(property "Value" "SCD1U50V3KX-GP"
			(at -0.0254 -2.0193 0)
			(unlocked yes)
			(layer "F.Fab")
			(hide yes)
			(effects
				(font
					(size 1.016 1.016)
					(thickness 0.1524)
				)
			)
		)
		(property "Device Type" "C603H36"
			(at -0.0254 -3.5433 0)
			(unlocked yes)
			(layer "F.Fab")
			(hide yes)
			(effects
				(font
					(size 1.016 1.016)
					(thickness 0.1524)
				)
			)
		)
		(duplicate_pad_numbers_are_jumpers no)
		(fp_line
			(start -0.4064 0)
			(end 0.4064 0)
			(stroke
				(width 0.2286)
				(type default)
			)
			(layer "F.SilkS")
		)
		(fp_rect
			(start -0.635 1.1811)
			(end 0.635 -1.1811)
			(stroke
				(width 0)
				(type default)
			)
			(fill no)
			(layer "F.CrtYd")
		)
		(fp_rect
			(start -0.635 1.1811)
			(end 0.635 -1.1811)
			(stroke
				(width 0)
				(type default)
			)
			(fill no)
			(layer "F.Fab")
		)
		(pad "1" smd custom
			(at 0 -0.6604)
			(size 0.19685 0.19685)
			(layers "F.Cu" "F.Mask" "F.Paste")
			(net "P1V0_VBST")
			(options
				(clearance outline)
				(anchor circle)
			)
			(primitives
				(gr_poly
					(pts
						(arc
							(start 0.508 -0.2921)
							(mid 0.478242 -0.363942)
							(end 0.4064 -0.3937)
						)
						(arc
							(start -0.4064 -0.3937)
							(mid -0.478242 -0.363942)
							(end -0.508 -0.2921)
						)
						(arc
							(start -0.508 0.2921)
							(mid -0.478242 0.363942)
							(end -0.4064 0.3937)
						)
						(arc
							(start 0.4064 0.3937)
							(mid 0.478242 0.363942)
							(end 0.508 0.2921)
						)
					)
					(width 0)
					(fill yes)
				)
			)
		)
		(pad "2" smd custom
			(at 0 0.6604)
			(size 0.19685 0.19685)
			(layers "F.Cu" "F.Mask" "F.Paste")
			(net "P1V0_VBST_RC")
			(options
				(clearance outline)
				(anchor circle)
			)
			(primitives
				(gr_poly
					(pts
						(arc
							(start 0.508 -0.2921)
							(mid 0.478242 -0.363942)
							(end 0.4064 -0.3937)
						)
						(arc
							(start -0.4064 -0.3937)
							(mid -0.478242 -0.363942)
							(end -0.508 -0.2921)
						)
						(arc
							(start -0.508 0.2921)
							(mid -0.478242 0.363942)
							(end -0.4064 0.3937)
						)
						(arc
							(start 0.4064 0.3937)
							(mid 0.478242 0.363942)
							(end 0.508 0.2921)
						)
					)
					(width 0)
					(fill yes)
				)
			)
		)
	)
)
